# BASEBOARD_FAB2 (Tioga Pass) — schematic netlist excerpt (pin names and nets, part order shuffled) for the footprints in the layout excerpt that follows; sources: Cadence DE-HDL packaged netlist, KiCad conversion of Wiwynn_Tioga_Pass_MB.brd

C7W2  SE100U16VM-48-GP  pkg SMD-TCG2  page 220 : \1\ = VR_FET_SW_P12V_STBY_PVDDQ_DEF ; \2\ = GND
C4G14  CAP  1000PF 50V 10% X7R  pkg 0402LF  page 221 : A = PWRGD_PVTT_ABC_CPU0_R ; B = GND

(kicad_pcb
	(version 20260206)
	(generator "pcbnew")
	(generator_version "10.0")
	(general
		(thickness 1.6)
		(legacy_teardrops no)
	)
	(paper "A4")
	(title_block
		(title "Wiwynn_Tioga_Pass_MB.brd")
		(comment 1 "Tioga Pass / footprints 2054-2055 of 4770")
	)
	(layers
		(0 "F.Cu" signal "TOP")
		(4 "In1.Cu" signal "L2GND")
		(6 "In2.Cu" signal "L3")
		(8 "In3.Cu" signal "L4GND")
		(10 "In4.Cu" signal "L5")
		(12 "In5.Cu" signal "L6GND")
		(14 "In6.Cu" signal "L7VCC")
		(16 "In7.Cu" signal "L8VCC")
		(18 "In8.Cu" signal "L9GND")
		(20 "In9.Cu" signal "L10")
		(22 "In10.Cu" signal "L11GND")
		(24 "In11.Cu" signal "L12")
		(26 "In12.Cu" signal "L13GND")
		(2 "B.Cu" signal "BOTTOM")
		(9 "F.Adhes" user "F.Adhesive")
		(11 "B.Adhes" user "B.Adhesive")
		(13 "F.Paste" user "Package Geometry/Pastemask Top")
		(15 "B.Paste" user "Package Geometry/Pastemask Bottom")
		(5 "F.SilkS" user "Ref Des/Silkscreen Top")
		(7 "B.SilkS" user "Ref Des/Silkscreen Bottom")
		(1 "F.Mask" user "Board Geometry/Soldermask Top")
		(3 "B.Mask" user "Board Geometry/Soldermask Bottom")
		(17 "Dwgs.User" user "User.Drawings")
		(19 "Cmts.User" user "User.Comments")
		(21 "Eco1.User" user "User.Eco1")
		(23 "Eco2.User" user "User.Eco2")
		(25 "Edge.Cuts" user "Board Geometry/Outline")
		(27 "Margin" user)
		(31 "F.CrtYd" user "Package Geometry/Place Bound Top")
		(29 "B.CrtYd" user "Package Geometry/Place Bound Bottom")
		(35 "F.Fab" user "Ref Des/Assembly Top")
		(33 "B.Fab" user "Ref Des/Assembly Bottom")
	)
	(footprint ""
		(layer "F.Cu")
		(at 357.0605 -146.61642)
		(property "Reference" "C7W2"
			(at 0 0 0)
			(layer "F.SilkS")
			(hide yes)
			(effects
				(font
					(size 1.27 1.27)
				)
			)
		)
		(property "Value" "*"
			(at 3.5941 -1.41605 0)
			(unlocked yes)
			(layer "F.Fab")
			(hide yes)
			(effects
				(font
					(size 0.889 0.889)
					(thickness 0.1524)
				)
			)
		)
		(property "Device Type" "SE100U16VM-48-GP_SMD-TCG2-SE10A"
			(at 3.5941 -2.94005 0)
			(unlocked yes)
			(layer "F.Fab")
			(hide yes)
			(effects
				(font
					(size 0.889 0.889)
					(thickness 0.1524)
				)
			)
		)
		(duplicate_pad_numbers_are_jumpers no)
		(fp_line
			(start -2.7559 -2.0955)
			(end -2.0955 -2.7559)
			(stroke
				(width 0.1524)
				(type default)
			)
			(layer "F.SilkS")
		)
		(fp_line
			(start -2.7559 2.7559)
			(end -2.7559 -2.0955)
			(stroke
				(width 0.1524)
				(type default)
			)
			(layer "F.SilkS")
		)
		(fp_line
			(start -2.0955 -2.7559)
			(end -1.0287 -2.7559)
			(stroke
				(width 0.1524)
				(type default)
			)
			(layer "F.SilkS")
		)
		(fp_line
			(start -1.0287 2.7559)
			(end -2.7559 2.7559)
			(stroke
				(width 0.1524)
				(type default)
			)
			(layer "F.SilkS")
		)
		(fp_line
			(start 1.0287 -2.7559)
			(end 2.0955 -2.7559)
			(stroke
				(width 0.1524)
				(type default)
			)
			(layer "F.SilkS")
		)
		(fp_line
			(start 2.0955 -2.7559)
			(end 2.7559 -2.0955)
			(stroke
				(width 0.1524)
				(type default)
			)
			(layer "F.SilkS")
		)
		(fp_line
			(start 2.7559 -2.0955)
			(end 2.7559 2.7559)
			(stroke
				(width 0.1524)
				(type default)
			)
			(layer "F.SilkS")
		)
		(fp_line
			(start 2.7559 2.7559)
			(end 1.0287 2.7559)
			(stroke
				(width 0.1524)
				(type default)
			)
			(layer "F.SilkS")
		)
		(fp_poly
			(pts
				(xy -0.8001 3.7084) (xy -0.8001 2.7559) (xy -2.7559 2.7559) (xy -2.7559 -2.7559) (xy -0.8001 -2.7559)
				(xy -0.8001 -3.7084) (xy 0.8001 -3.7084) (xy 0.8001 -2.7559) (xy 2.7559 -2.7559) (xy 2.7559 2.7559)
				(xy 0.8001 2.7559) (xy 0.8001 3.7084)
			)
			(stroke
				(width 0)
				(type default)
			)
			(fill no)
			(layer "F.CrtYd")
		)
		(fp_poly
			(pts
				(xy -0.8001 3.7084) (xy -0.8001 2.7559) (xy -2.7559 2.7559) (xy -2.7559 -2.7559) (xy -0.8001 -2.7559)
				(xy -0.8001 -3.7084) (xy 0.8001 -3.7084) (xy 0.8001 -2.7559) (xy 2.7559 -2.7559) (xy 2.7559 2.7559)
				(xy 0.8001 2.7559) (xy 0.8001 3.7084)
			)
			(stroke
				(width 0)
				(type default)
			)
			(fill no)
			(layer "F.Fab")
		)
		(pad "1" smd rect
			(at 0 -2.199894)
			(size 1.6002 2.9972)
			(layers "F.Cu" "F.Mask" "F.Paste")
			(net "VR_FET_SW_P12V_STBY_PVDDQ_DEF")
		)
		(pad "2" smd rect
			(at 0 2.199894)
			(size 1.6002 2.9972)
			(layers "F.Cu" "F.Mask" "F.Paste")
			(net "GND")
		)
	)
	(footprint ""
		(layer "F.Cu")
		(at 181.847998 -4.432808 180)
		(property "Reference" "C4G14"
			(at 0 0 180)
			(layer "F.SilkS")
			(hide yes)
			(effects
				(font
					(size 1.27 1.27)
				)
			)
		)
		(property "Value" ""
			(at 0 0 180)
			(layer "F.Fab")
			(effects
				(font
					(size 1.27 1.27)
				)
			)
		)
		(duplicate_pad_numbers_are_jumpers no)
		(fp_rect
			(start 0.3048 0.9906)
			(end -0.3048 -0.1016)
			(stroke
				(width 0)
				(type default)
			)
			(fill no)
			(layer "F.CrtYd")
		)
		(fp_line
			(start 0.3048 0.9906)
			(end 0.3048 -0.1016)
			(stroke
				(width 0.1)
				(type default)
			)
			(layer "F.Fab")
		)
		(fp_line
			(start 0.3048 -0.1016)
			(end -0.3048 -0.1016)
			(stroke
				(width 0.1)
				(type default)
			)
			(layer "F.Fab")
		)
		(fp_line
			(start -0.3048 0.9906)
			(end 0.3048 0.9906)
			(stroke
				(width 0.1)
				(type default)
			)
			(layer "F.Fab")
		)
		(fp_line
			(start -0.3048 -0.1016)
			(end -0.3048 0.9906)
			(stroke
				(width 0.1)
				(type default)
			)
			(layer "F.Fab")
		)
		(pad "1" smd rect
			(at 0 0 180)
			(size 0.508 0.508)
			(layers "F.Cu" "F.Mask" "F.Paste")
			(net "PWRGD_PVTT_ABC_CPU0_R")
		)
		(pad "2" smd rect
			(at 0 0.889 180)
			(size 0.508 0.508)
			(layers "F.Cu" "F.Mask" "F.Paste")
			(net "GND")
		)
		(zone
			(layer "F.Cu")
			(hatch none 0.5)
			(connect_pads
				(clearance 0)
			)
			(min_thickness 0.25)
			(keepout
				(tracks allowed)
				(vias not_allowed)
				(pads allowed)
				(copperpour not_allowed)
				(footprints allowed)
			)
			(placement
				(enabled no)
				(sheetname "")
			)
			(fill
				(thermal_gap 0.5)
				(thermal_bridge_width 0.5)
				(island_removal_mode 0)
			)
			(polygon
				(pts
					(xy 181.593998 -5.067808) (xy 181.593998 -4.686808) (xy 182.101998 -4.686808) (xy 182.101998 -5.067808)
				)
			)
		)
		(zone
			(layer "F.Cu")
			(hatch none 0.5)
			(connect_pads
				(clearance 0)
			)
			(min_thickness 0.25)
			(keepout
				(tracks not_allowed)
				(vias allowed)
				(pads allowed)
				(copperpour not_allowed)
				(footprints allowed)
			)
			(placement
				(enabled no)
				(sheetname "")
			)
			(fill
				(thermal_gap 0.5)
				(thermal_bridge_width 0.5)
				(island_removal_mode 0)
			)
			(polygon
				(pts
					(xy 181.593998 -5.067808) (xy 181.593998 -4.686808) (xy 182.101998 -4.686808) (xy 182.101998 -5.067808)
				)
			)
		)
	)
)
